FILE_TYPE = CONNECTIVITY;
{Allegro Design Entry HDL 17.2-2016 S081 (4005846) 1/11/2022}
"PAGE_NUMBER" = 19;
0"NC";
END.
